# SCM (Grand Teton) — schematic netlist excerpt (pin names and nets, part order shuffled) for the footprints in the layout excerpt that follows; sources: Cadence DE-HDL packaged netlist, KiCad conversion of 12092022_DA0F0TMDCD0_F0T_Management_Board_D_brd_V3_OCP.brd

R429  Q_RES  2.2K 5% CHIP  pkg 0402LF  page 27 : A = P3V3_AUX ; B = SMB_BMC_MM14_SCL
R866  Q_RES  10K 1% CHIP  pkg 0402LF  page 44 : A = FM_BMC_BIOS_MUX_CS_SPI_R_SEL_0 ; B = GND

(kicad_pcb
	(version 20260206)
	(generator "pcbnew")
	(generator_version "10.0")
	(general
		(thickness 1.6)
		(legacy_teardrops no)
	)
	(paper "A4")
	(title_block
		(title "12092022_DA0F0TMDCD0_F0T_Management_Board_D_brd_V3_OCP.brd")
		(comment 1 "Grand Teton / footprints 1049-1050 of 1440")
	)
	(layers
		(0 "F.Cu" signal "TOP")
		(4 "In1.Cu" signal "GND")
		(6 "In2.Cu" signal "IN1")
		(8 "In3.Cu" signal "GND1")
		(10 "In4.Cu" signal "IN2")
		(12 "In5.Cu" signal "VCC")
		(14 "In6.Cu" signal "VCC1")
		(16 "In7.Cu" signal "IN3")
		(18 "In8.Cu" signal "GND2")
		(20 "In9.Cu" signal "IN4")
		(22 "In10.Cu" signal "GND3")
		(2 "B.Cu" signal "BOTTOM")
		(9 "F.Adhes" user "F.Adhesive")
		(11 "B.Adhes" user "B.Adhesive")
		(13 "F.Paste" user "Package Geometry/Pastemask Top")
		(15 "B.Paste" user "Package Geometry/Pastemask Bottom")
		(5 "F.SilkS" user "Ref Des/Silkscreen Top")
		(7 "B.SilkS" user "Ref Des/Silkscreen Bottom")
		(1 "F.Mask" user "Board Geometry/Soldermask Top")
		(3 "B.Mask" user "Board Geometry/Soldermask Bottom")
		(17 "Dwgs.User" user "User.Drawings")
		(19 "Cmts.User" user "User.Comments")
		(21 "Eco1.User" user "User.Eco1")
		(23 "Eco2.User" user "User.Eco2")
		(25 "Edge.Cuts" user "Board Geometry/Outline")
		(27 "Margin" user)
		(31 "F.CrtYd" user "Package Geometry/Place Bound Top")
		(29 "B.CrtYd" user "Package Geometry/Place Bound Bottom")
		(35 "F.Fab" user "Ref Des/Assembly Top")
		(33 "B.Fab" user "Ref Des/Assembly Bottom")
	)
	(footprint ""
		(layer "B.Cu")
		(at 37.867336 -48.9204 180)
		(property "Reference" "R429"
			(at 0 0 0)
			(layer "B.SilkS")
			(hide yes)
			(effects
				(font
					(size 1.27 1.27)
				)
				(justify mirror)
			)
		)
		(property "Value" ""
			(at 0 0 0)
			(layer "B.Fab")
			(effects
				(font
					(size 1.27 1.27)
				)
				(justify mirror)
			)
		)
		(duplicate_pad_numbers_are_jumpers no)
		(fp_line
			(start 0.7874 0.4064)
			(end 0.7874 -0.4064)
			(stroke
				(width 0.1524)
				(type default)
			)
			(layer "B.SilkS")
		)
		(fp_line
			(start 0.7874 -0.4064)
			(end -0.7874 -0.4064)
			(stroke
				(width 0.1524)
				(type default)
			)
			(layer "B.SilkS")
		)
		(fp_line
			(start -0.7874 0.4064)
			(end 0.7874 0.4064)
			(stroke
				(width 0.1524)
				(type default)
			)
			(layer "B.SilkS")
		)
		(fp_line
			(start -0.7874 -0.4064)
			(end -0.7874 0.4064)
			(stroke
				(width 0.1524)
				(type default)
			)
			(layer "B.SilkS")
		)
		(fp_line
			(start 0.67945 0.3048)
			(end 0.67945 -0.305054)
			(stroke
				(width 0.1)
				(type default)
			)
			(layer "B.Fab")
		)
		(fp_line
			(start 0.67945 -0.305054)
			(end 0.12065 -0.305054)
			(stroke
				(width 0.1)
				(type default)
			)
			(layer "B.Fab")
		)
		(fp_line
			(start 0.12065 0.3048)
			(end 0.67945 0.3048)
			(stroke
				(width 0.1)
				(type default)
			)
			(layer "B.Fab")
		)
		(fp_line
			(start 0.12065 0.2794)
			(end 0.12065 0.3048)
			(stroke
				(width 0.1)
				(type default)
			)
			(layer "B.Fab")
		)
		(fp_line
			(start 0.12065 -0.2794)
			(end -0.12065 -0.2794)
			(stroke
				(width 0.1)
				(type default)
			)
			(layer "B.Fab")
		)
		(fp_line
			(start 0.12065 -0.305054)
			(end 0.12065 -0.2794)
			(stroke
				(width 0.1)
				(type default)
			)
			(layer "B.Fab")
		)
		(fp_line
			(start -0.120396 0.3048)
			(end -0.120396 0.2794)
			(stroke
				(width 0.1)
				(type default)
			)
			(layer "B.Fab")
		)
		(fp_line
			(start -0.120396 0.2794)
			(end 0.12065 0.2794)
			(stroke
				(width 0.1)
				(type default)
			)
			(layer "B.Fab")
		)
		(fp_line
			(start -0.12065 -0.2794)
			(end -0.12065 -0.3048)
			(stroke
				(width 0.1)
				(type default)
			)
			(layer "B.Fab")
		)
		(fp_line
			(start -0.12065 -0.3048)
			(end -0.67945 -0.3048)
			(stroke
				(width 0.1)
				(type default)
			)
			(layer "B.Fab")
		)
		(fp_line
			(start -0.67945 0.3048)
			(end -0.120396 0.3048)
			(stroke
				(width 0.1)
				(type default)
			)
			(layer "B.Fab")
		)
		(fp_line
			(start -0.67945 -0.3048)
			(end -0.67945 0.3048)
			(stroke
				(width 0.1)
				(type default)
			)
			(layer "B.Fab")
		)
		(pad "1" smd circle
			(at 0.40005 0)
			(size 0 0)
			(layers "B.Cu" "B.Mask" "B.Paste")
			(net "P3V3_AUX")
		)
		(pad "2" smd circle
			(at -0.40005 0)
			(size 0 0)
			(layers "B.Cu" "B.Mask" "B.Paste")
			(net "SMB_BMC_MM14_SCL")
		)
	)
	(footprint ""
		(layer "B.Cu")
		(at 49.7967 -104.2035 180)
		(property "Reference" "R866"
			(at 0 0 0)
			(layer "B.SilkS")
			(hide yes)
			(effects
				(font
					(size 1.27 1.27)
				)
				(justify mirror)
			)
		)
		(property "Value" ""
			(at 0 0 0)
			(layer "B.Fab")
			(effects
				(font
					(size 1.27 1.27)
				)
				(justify mirror)
			)
		)
		(duplicate_pad_numbers_are_jumpers no)
		(fp_line
			(start 0.7874 0.4064)
			(end 0.7874 -0.4064)
			(stroke
				(width 0.1524)
				(type default)
			)
			(layer "B.SilkS")
		)
		(fp_line
			(start 0.7874 -0.4064)
			(end -0.7874 -0.4064)
			(stroke
				(width 0.1524)
				(type default)
			)
			(layer "B.SilkS")
		)
		(fp_line
			(start -0.7874 0.4064)
			(end 0.7874 0.4064)
			(stroke
				(width 0.1524)
				(type default)
			)
			(layer "B.SilkS")
		)
		(fp_line
			(start -0.7874 -0.4064)
			(end -0.7874 0.4064)
			(stroke
				(width 0.1524)
				(type default)
			)
			(layer "B.SilkS")
		)
		(fp_line
			(start 0.67945 0.3048)
			(end 0.67945 -0.305054)
			(stroke
				(width 0.1)
				(type default)
			)
			(layer "B.Fab")
		)
		(fp_line
			(start 0.67945 -0.305054)
			(end 0.12065 -0.305054)
			(stroke
				(width 0.1)
				(type default)
			)
			(layer "B.Fab")
		)
		(fp_line
			(start 0.12065 0.3048)
			(end 0.67945 0.3048)
			(stroke
				(width 0.1)
				(type default)
			)
			(layer "B.Fab")
		)
		(fp_line
			(start 0.12065 0.2794)
			(end 0.12065 0.3048)
			(stroke
				(width 0.1)
				(type default)
			)
			(layer "B.Fab")
		)
		(fp_line
			(start 0.12065 -0.2794)
			(end -0.12065 -0.2794)
			(stroke
				(width 0.1)
				(type default)
			)
			(layer "B.Fab")
		)
		(fp_line
			(start 0.12065 -0.305054)
			(end 0.12065 -0.2794)
			(stroke
				(width 0.1)
				(type default)
			)
			(layer "B.Fab")
		)
		(fp_line
			(start -0.120396 0.3048)
			(end -0.120396 0.2794)
			(stroke
				(width 0.1)
				(type default)
			)
			(layer "B.Fab")
		)
		(fp_line
			(start -0.120396 0.2794)
			(end 0.12065 0.2794)
			(stroke
				(width 0.1)
				(type default)
			)
			(layer "B.Fab")
		)
		(fp_line
			(start -0.12065 -0.2794)
			(end -0.12065 -0.3048)
			(stroke
				(width 0.1)
				(type default)
			)
			(layer "B.Fab")
		)
		(fp_line
			(start -0.12065 -0.3048)
			(end -0.67945 -0.3048)
			(stroke
				(width 0.1)
				(type default)
			)
			(layer "B.Fab")
		)
		(fp_line
			(start -0.67945 0.3048)
			(end -0.120396 0.3048)
			(stroke
				(width 0.1)
				(type default)
			)
			(layer "B.Fab")
		)
		(fp_line
			(start -0.67945 -0.3048)
			(end -0.67945 0.3048)
			(stroke
				(width 0.1)
				(type default)
			)
			(layer "B.Fab")
		)
		(pad "1" smd circle
			(at 0.40005 0)
			(size 0 0)
			(layers "B.Cu" "B.Mask" "B.Paste")
			(net "FM_BMC_BIOS_MUX_CS_SPI_R_SEL_0")
		)
		(pad "2" smd circle
			(at -0.40005 0)
			(size 0 0)
			(layers "B.Cu" "B.Mask" "B.Paste")
			(net "GND")
		)
	)
)
